# BASEBOARD_FAB2 (Tioga Pass) — schematic netlist excerpt (pin names and nets, part order shuffled) for the footprints in the layout excerpt that follows; sources: Cadence DE-HDL packaged netlist, KiCad conversion of Wiwynn_Tioga_Pass_MB.brd

R4T2  RES  0.0 5% EMPTY  pkg 0402  page 89 : A = FM_ADR_COMPLETE ; B = FM_ADR_COMPLETE_R
C3L9  CAP  10UF 16V 10% X6S  pkg 0805  page 236 : A = VR_FET_SW_P12V_STBY_PVDDQ_DEF ; B = GND
C22W32  SC22U16V5MX-4-GP  20%  pkg SMD-BCG5  page 212 : \1\ = VR_FET_SW_P12V_STBY_PVCCIO_CPU0 ; \2\ = GND

(kicad_pcb
	(version 20260206)
	(generator "pcbnew")
	(generator_version "10.0")
	(general
		(thickness 1.6)
		(legacy_teardrops no)
	)
	(paper "A4")
	(title_block
		(title "Wiwynn_Tioga_Pass_MB.brd")
		(comment 1 "Tioga Pass / footprints 3010-3012 of 4770")
	)
	(layers
		(0 "F.Cu" signal "TOP")
		(4 "In1.Cu" signal "L2GND")
		(6 "In2.Cu" signal "L3")
		(8 "In3.Cu" signal "L4GND")
		(10 "In4.Cu" signal "L5")
		(12 "In5.Cu" signal "L6GND")
		(14 "In6.Cu" signal "L7VCC")
		(16 "In7.Cu" signal "L8VCC")
		(18 "In8.Cu" signal "L9GND")
		(20 "In9.Cu" signal "L10")
		(22 "In10.Cu" signal "L11GND")
		(24 "In11.Cu" signal "L12")
		(26 "In12.Cu" signal "L13GND")
		(2 "B.Cu" signal "BOTTOM")
		(9 "F.Adhes" user "F.Adhesive")
		(11 "B.Adhes" user "B.Adhesive")
		(13 "F.Paste" user "Package Geometry/Pastemask Top")
		(15 "B.Paste" user "Package Geometry/Pastemask Bottom")
		(5 "F.SilkS" user "Ref Des/Silkscreen Top")
		(7 "B.SilkS" user "Ref Des/Silkscreen Bottom")
		(1 "F.Mask" user "Board Geometry/Soldermask Top")
		(3 "B.Mask" user "Board Geometry/Soldermask Bottom")
		(17 "Dwgs.User" user "User.Drawings")
		(19 "Cmts.User" user "User.Comments")
		(21 "Eco1.User" user "User.Eco1")
		(23 "Eco2.User" user "User.Eco2")
		(25 "Edge.Cuts" user "Board Geometry/Outline")
		(27 "Margin" user)
		(31 "F.CrtYd" user "Package Geometry/Place Bound Top")
		(29 "B.CrtYd" user "Package Geometry/Place Bound Bottom")
		(35 "F.Fab" user "Ref Des/Assembly Top")
		(33 "B.Fab" user "Ref Des/Assembly Bottom")
	)
	(footprint ""
		(layer "B.Cu")
		(at 318.9732 -33.1978 -90)
		(property "Reference" "R4T2"
			(at 0 0 90)
			(layer "B.SilkS")
			(hide yes)
			(effects
				(font
					(size 1.27 1.27)
				)
				(justify mirror)
			)
		)
		(property "Value" ""
			(at 0 0 90)
			(layer "B.Fab")
			(effects
				(font
					(size 1.27 1.27)
				)
				(justify mirror)
			)
		)
		(duplicate_pad_numbers_are_jumpers no)
		(fp_poly
			(pts
				(xy 0.2794 -0.1016) (xy -0.2794 -0.1016) (xy -0.2794 0.9906) (xy 0.2794 0.9906)
			)
			(stroke
				(width 0)
				(type default)
			)
			(fill no)
			(layer "B.CrtYd")
		)
		(fp_line
			(start -0.2794 0.9906)
			(end -0.2794 -0.1016)
			(stroke
				(width 0.1)
				(type default)
			)
			(layer "B.Fab")
		)
		(fp_line
			(start 0.2794 0.9906)
			(end -0.2794 0.9906)
			(stroke
				(width 0.1)
				(type default)
			)
			(layer "B.Fab")
		)
		(fp_line
			(start -0.2794 -0.1016)
			(end 0.2794 -0.1016)
			(stroke
				(width 0.1)
				(type default)
			)
			(layer "B.Fab")
		)
		(fp_line
			(start 0.2794 -0.1016)
			(end 0.2794 0.9906)
			(stroke
				(width 0.1)
				(type default)
			)
			(layer "B.Fab")
		)
		(pad "1" smd rect
			(at 0 0 90)
			(size 0.508 0.508)
			(layers "B.Cu" "B.Mask" "B.Paste")
			(net "FM_ADR_COMPLETE")
		)
		(pad "2" smd rect
			(at 0 0.889 90)
			(size 0.508 0.508)
			(layers "B.Cu" "B.Mask" "B.Paste")
			(net "FM_ADR_COMPLETE_R")
		)
		(zone
			(layer "B.Cu")
			(hatch none 0.5)
			(connect_pads
				(clearance 0)
			)
			(min_thickness 0.25)
			(keepout
				(tracks not_allowed)
				(vias allowed)
				(pads allowed)
				(copperpour not_allowed)
				(footprints allowed)
			)
			(placement
				(enabled no)
				(sheetname "")
			)
			(fill
				(thermal_gap 0.5)
				(thermal_bridge_width 0.5)
				(island_removal_mode 0)
			)
			(polygon
				(pts
					(xy 318.3382 -32.9438) (xy 318.3382 -33.4518) (xy 318.7192 -33.4518) (xy 318.7192 -32.9438)
				)
			)
		)
		(zone
			(layer "B.Cu")
			(hatch none 0.5)
			(connect_pads
				(clearance 0)
			)
			(min_thickness 0.25)
			(keepout
				(tracks allowed)
				(vias not_allowed)
				(pads allowed)
				(copperpour not_allowed)
				(footprints allowed)
			)
			(placement
				(enabled no)
				(sheetname "")
			)
			(fill
				(thermal_gap 0.5)
				(thermal_bridge_width 0.5)
				(island_removal_mode 0)
			)
			(polygon
				(pts
					(xy 318.7192 -32.9438) (xy 318.7192 -33.4518) (xy 318.3382 -33.4518) (xy 318.3382 -32.9438)
				)
			)
		)
	)
	(footprint ""
		(layer "B.Cu")
		(at 386.503672 -154.721306)
		(property "Reference" "C3L9"
			(at 0 0 0)
			(layer "B.SilkS")
			(hide yes)
			(effects
				(font
					(size 1.27 1.27)
				)
				(justify mirror)
			)
		)
		(property "Value" ""
			(at 0 0 0)
			(layer "B.Fab")
			(effects
				(font
					(size 1.27 1.27)
				)
				(justify mirror)
			)
		)
		(duplicate_pad_numbers_are_jumpers no)
		(fp_poly
			(pts
				(xy 0.7239 -0.2159) (xy -0.7239 -0.2159) (xy -0.7239 1.9939) (xy 0.7239 1.9939)
			)
			(stroke
				(width 0)
				(type default)
			)
			(fill no)
			(layer "B.CrtYd")
		)
		(fp_line
			(start -0.7239 -0.2159)
			(end 0.7239 -0.2159)
			(stroke
				(width 0.1)
				(type default)
			)
			(layer "B.Fab")
		)
		(fp_line
			(start -0.7239 1.9939)
			(end -0.7239 -0.2159)
			(stroke
				(width 0.1)
				(type default)
			)
			(layer "B.Fab")
		)
		(fp_line
			(start 0.7239 -0.2159)
			(end 0.7239 1.9939)
			(stroke
				(width 0.1)
				(type default)
			)
			(layer "B.Fab")
		)
		(fp_line
			(start 0.7239 1.9939)
			(end -0.7239 1.9939)
			(stroke
				(width 0.1)
				(type default)
			)
			(layer "B.Fab")
		)
		(pad "1" smd rect
			(at 0 0 180)
			(size 1.27 1.016)
			(layers "B.Cu" "B.Mask" "B.Paste")
			(net "VR_FET_SW_P12V_STBY_PVDDQ_DEF")
		)
		(pad "2" smd rect
			(at 0 1.778 180)
			(size 1.27 1.016)
			(layers "B.Cu" "B.Mask" "B.Paste")
			(net "GND")
		)
		(zone
			(layer "B.Cu")
			(hatch none 0.5)
			(connect_pads
				(clearance 0)
			)
			(min_thickness 0.25)
			(keepout
				(tracks not_allowed)
				(vias allowed)
				(pads allowed)
				(copperpour not_allowed)
				(footprints allowed)
			)
			(placement
				(enabled no)
				(sheetname "")
			)
			(fill
				(thermal_gap 0.5)
				(thermal_bridge_width 0.5)
				(island_removal_mode 0)
			)
			(polygon
				(pts
					(xy 387.138672 -154.213306) (xy 385.868672 -154.213306) (xy 385.868672 -153.451306) (xy 387.138672 -153.451306)
				)
			)
		)
	)
	(footprint ""
		(layer "B.Cu")
		(at 350.52 -104.267 180)
		(property "Reference" "C22W32"
			(at 0 0 0)
			(layer "B.SilkS")
			(hide yes)
			(effects
				(font
					(size 1.27 1.27)
				)
				(justify mirror)
			)
		)
		(property "Value" "*"
			(at 0.0762 -6.2357 180)
			(unlocked yes)
			(layer "B.Fab")
			(hide yes)
			(effects
				(font
					(size 1.27 1.016)
					(thickness 0.1524)
				)
				(justify mirror)
			)
		)
		(property "Device Type" "SC22U16V5MX-4-GP_SMD-BCG5-SC22A"
			(at 0.0762 -8.2677 180)
			(unlocked yes)
			(layer "B.Fab")
			(hide yes)
			(effects
				(font
					(size 1.27 1.016)
					(thickness 0.1524)
				)
				(justify mirror)
			)
		)
		(duplicate_pad_numbers_are_jumpers no)
		(fp_line
			(start -0.635 0)
			(end 0.635 0)
			(stroke
				(width 0.508)
				(type default)
			)
			(layer "B.SilkS")
		)
		(fp_rect
			(start 0.9652 1.778)
			(end -0.9652 -1.778)
			(stroke
				(width 0)
				(type default)
			)
			(fill no)
			(layer "B.CrtYd")
		)
		(fp_poly
			(pts
				(xy 0.9652 -1.778) (xy -0.9652 -1.778) (xy -0.9652 1.778) (xy 0.9652 1.778)
			)
			(stroke
				(width 0)
				(type default)
			)
			(fill no)
			(layer "B.Fab")
		)
		(pad "1" smd rect
			(at 0 -0.9652)
			(size 1.397 1.143)
			(layers "B.Cu" "B.Mask" "B.Paste")
			(net "VR_FET_SW_P12V_STBY_PVCCIO_CPU0")
		)
		(pad "2" smd rect
			(at 0 0.9652)
			(size 1.397 1.143)
			(layers "B.Cu" "B.Mask" "B.Paste")
			(net "GND")
		)
	)
)
